(kicad_pcb
	(version 20260206)
	(generator "pcbnew")
	(generator_version "10.0")
	(general
		(thickness 1.6)
		(legacy_teardrops no)
	)
	(paper "A4")
	(title_block
		(title "03242023_DA0F0TMBIJ0_F0T_Motherboard_J_brd_V01_OCP.brd")
		(comment 1 "Grand Teton / footprints 3564-3568 of 6105")
	)
	(layers
		(0 "F.Cu" signal "TOP")
		(4 "In1.Cu" signal "GND")
		(6 "In2.Cu" signal "IN1")
		(8 "In3.Cu" signal "GND1")
		(10 "In4.Cu" signal "IN2")
		(12 "In5.Cu" signal "GND2")
		(14 "In6.Cu" signal "IN3")
		(16 "In7.Cu" signal "GND3")
		(18 "In8.Cu" signal "VCC")
		(20 "In9.Cu" signal "VCC1")
		(22 "In10.Cu" signal "GND4")
		(24 "In11.Cu" signal "IN4")
		(26 "In12.Cu" signal "GND5")
		(28 "In13.Cu" signal "IN5")
		(30 "In14.Cu" signal "GND6")
		(32 "In15.Cu" signal "IN6")
		(34 "In16.Cu" signal "GND7")
		(2 "B.Cu" signal "BOTTOM")
		(9 "F.Adhes" user "F.Adhesive")
		(11 "B.Adhes" user "B.Adhesive")
		(13 "F.Paste" user "Package Geometry/Pastemask Top")
		(15 "B.Paste" user "Package Geometry/Pastemask Bottom")
		(5 "F.SilkS" user "Ref Des/Silkscreen Top")
		(7 "B.SilkS" user "Ref Des/Silkscreen Bottom")
		(1 "F.Mask" user "Board Geometry/Soldermask Top")
		(3 "B.Mask" user "Board Geometry/Soldermask Bottom")
		(17 "Dwgs.User" user "User.Drawings")
		(19 "Cmts.User" user "User.Comments")
		(21 "Eco1.User" user "User.Eco1")
		(23 "Eco2.User" user "User.Eco2")
		(25 "Edge.Cuts" user "Board Geometry/Outline")
		(27 "Margin" user)
		(31 "F.CrtYd" user "Package Geometry/Place Bound Top")
		(29 "B.CrtYd" user "Package Geometry/Place Bound Bottom")
		(35 "F.Fab" user "Ref Des/Assembly Top")
		(33 "B.Fab" user "Ref Des/Assembly Bottom")
	)
	(footprint ""
		(layer "F.Cu")
		(at 101.833934 -391.61974)
		(property "Reference" "R3461"
			(at 0 0 0)
			(layer "F.SilkS")
			(hide yes)
			(effects
				(font
					(size 1.27 1.27)
				)
			)
		)
		(property "Value" ""
			(at 0 0 0)
			(layer "F.Fab")
			(effects
				(font
					(size 1.27 1.27)
				)
			)
		)
		(duplicate_pad_numbers_are_jumpers no)
		(fp_line
			(start -0.7874 -0.4064)
			(end 0.7874 -0.4064)
			(stroke
				(width 0.1524)
				(type default)
			)
			(layer "F.SilkS")
		)
		(fp_line
			(start -0.7874 0.4064)
			(end -0.7874 -0.4064)
			(stroke
				(width 0.1524)
				(type default)
			)
			(layer "F.SilkS")
		)
		(fp_line
			(start 0.7874 -0.4064)
			(end 0.7874 0.4064)
			(stroke
				(width 0.1524)
				(type default)
			)
			(layer "F.SilkS")
		)
		(fp_line
			(start 0.7874 0.4064)
			(end -0.7874 0.4064)
			(stroke
				(width 0.1524)
				(type default)
			)
			(layer "F.SilkS")
		)
		(fp_line
			(start -0.67945 -0.305054)
			(end -0.12065 -0.305054)
			(stroke
				(width 0.1)
				(type default)
			)
			(layer "F.Fab")
		)
		(fp_line
			(start -0.67945 0.3048)
			(end -0.67945 -0.305054)
			(stroke
				(width 0.1)
				(type default)
			)
			(layer "F.Fab")
		)
		(fp_line
			(start -0.12065 -0.305054)
			(end -0.12065 -0.2794)
			(stroke
				(width 0.1)
				(type default)
			)
			(layer "F.Fab")
		)
		(fp_line
			(start -0.12065 -0.2794)
			(end 0.12065 -0.2794)
			(stroke
				(width 0.1)
				(type default)
			)
			(layer "F.Fab")
		)
		(fp_line
			(start -0.12065 0.2794)
			(end -0.12065 0.3048)
			(stroke
				(width 0.1)
				(type default)
			)
			(layer "F.Fab")
		)
		(fp_line
			(start -0.12065 0.3048)
			(end -0.67945 0.3048)
			(stroke
				(width 0.1)
				(type default)
			)
			(layer "F.Fab")
		)
		(fp_line
			(start 0.120396 0.2794)
			(end -0.12065 0.2794)
			(stroke
				(width 0.1)
				(type default)
			)
			(layer "F.Fab")
		)
		(fp_line
			(start 0.120396 0.3048)
			(end 0.120396 0.2794)
			(stroke
				(width 0.1)
				(type default)
			)
			(layer "F.Fab")
		)
		(fp_line
			(start 0.12065 -0.3048)
			(end 0.67945 -0.3048)
			(stroke
				(width 0.1)
				(type default)
			)
			(layer "F.Fab")
		)
		(fp_line
			(start 0.12065 -0.2794)
			(end 0.12065 -0.3048)
			(stroke
				(width 0.1)
				(type default)
			)
			(layer "F.Fab")
		)
		(fp_line
			(start 0.67945 -0.3048)
			(end 0.67945 0.3048)
			(stroke
				(width 0.1)
				(type default)
			)
			(layer "F.Fab")
		)
		(fp_line
			(start 0.67945 0.3048)
			(end 0.120396 0.3048)
			(stroke
				(width 0.1)
				(type default)
			)
			(layer "F.Fab")
		)
		(pad "1" smd circle
			(at -0.40005 0)
			(size 0 0)
			(layers "F.Cu" "F.Mask" "F.Paste")
			(net "P3V3_AUX")
		)
		(pad "2" smd circle
			(at 0.40005 0)
			(size 0 0)
			(layers "F.Cu" "F.Mask" "F.Paste")
			(net "GPU_NVS_PWR_BRAKE_N_R")
		)
	)
	(footprint ""
		(layer "F.Cu")
		(at 418.2491 -371.783356)
		(property "Reference" "PL101"
			(at -1.12014 -4.478528 0)
			(unlocked yes)
			(layer "F.SilkS")
			(effects
				(font
					(size 0.7874 0.5842)
					(thickness 0.1524)
				)
				(justify left)
			)
		)
		(property "Value" ""
			(at 0 0 0)
			(layer "F.Fab")
			(effects
				(font
					(size 1.27 1.27)
				)
			)
		)
		(duplicate_pad_numbers_are_jumpers no)
		(fp_line
			(start -2.249932 -2.249932)
			(end 2.249932 -2.249932)
			(stroke
				(width 0.1524)
				(type default)
			)
			(layer "F.SilkS")
		)
		(fp_line
			(start -2.249932 -1.3843)
			(end -2.249932 -2.249932)
			(stroke
				(width 0.1524)
				(type default)
			)
			(layer "F.SilkS")
		)
		(fp_line
			(start -2.249932 2.249932)
			(end -2.249932 1.3843)
			(stroke
				(width 0.1524)
				(type default)
			)
			(layer "F.SilkS")
		)
		(fp_line
			(start 2.249932 -2.249932)
			(end 2.249932 -1.3843)
			(stroke
				(width 0.1524)
				(type default)
			)
			(layer "F.SilkS")
		)
		(fp_line
			(start 2.249932 1.3843)
			(end 2.249932 2.249932)
			(stroke
				(width 0.1524)
				(type default)
			)
			(layer "F.SilkS")
		)
		(fp_line
			(start 2.249932 2.249932)
			(end -2.249932 2.249932)
			(stroke
				(width 0.1524)
				(type default)
			)
			(layer "F.SilkS")
		)
		(fp_line
			(start -2.249932 -2.249932)
			(end 2.249932 -2.249932)
			(stroke
				(width 0.1)
				(type default)
			)
			(layer "F.Fab")
		)
		(fp_line
			(start -2.249932 2.249932)
			(end -2.249932 -2.249932)
			(stroke
				(width 0.1)
				(type default)
			)
			(layer "F.Fab")
		)
		(fp_line
			(start 2.249932 -2.249932)
			(end 2.249932 2.249932)
			(stroke
				(width 0.1)
				(type default)
			)
			(layer "F.Fab")
		)
		(fp_line
			(start 2.249932 2.249932)
			(end -2.249932 2.249932)
			(stroke
				(width 0.1)
				(type default)
			)
			(layer "F.Fab")
		)
		(pad "1" smd rect
			(at -1.82499 0)
			(size 1.0668 2.5146)
			(layers "F.Cu" "F.Mask" "F.Paste")
			(net "P12V_AUX")
		)
		(pad "2" smd rect
			(at 1.82499 0)
			(size 1.0668 2.5146)
			(layers "F.Cu" "F.Mask" "F.Paste")
			(net "SW_P12V_PVCCFA_EHV_FIVRA_CPU0_R")
		)
	)
	(footprint ""
		(layer "F.Cu")
		(at 154.34945 -81.889346 -90)
		(property "Reference" "R3223"
			(at 0 0 270)
			(layer "F.SilkS")
			(hide yes)
			(effects
				(font
					(size 1.27 1.27)
				)
			)
		)
		(property "Value" ""
			(at 0 0 270)
			(layer "F.Fab")
			(effects
				(font
					(size 1.27 1.27)
				)
			)
		)
		(duplicate_pad_numbers_are_jumpers no)
		(fp_line
			(start -0.7874 0.4064)
			(end -0.7874 -0.4064)
			(stroke
				(width 0.1524)
				(type default)
			)
			(layer "F.SilkS")
		)
		(fp_line
			(start 0.7874 0.4064)
			(end -0.7874 0.4064)
			(stroke
				(width 0.1524)
				(type default)
			)
			(layer "F.SilkS")
		)
		(fp_line
			(start -0.7874 -0.4064)
			(end 0.7874 -0.4064)
			(stroke
				(width 0.1524)
				(type default)
			)
			(layer "F.SilkS")
		)
		(fp_line
			(start 0.7874 -0.4064)
			(end 0.7874 0.4064)
			(stroke
				(width 0.1524)
				(type default)
			)
			(layer "F.SilkS")
		)
		(fp_line
			(start -0.67945 0.3048)
			(end -0.67945 -0.305054)
			(stroke
				(width 0.1)
				(type default)
			)
			(layer "F.Fab")
		)
		(fp_line
			(start -0.12065 0.3048)
			(end -0.67945 0.3048)
			(stroke
				(width 0.1)
				(type default)
			)
			(layer "F.Fab")
		)
		(fp_line
			(start 0.120396 0.3048)
			(end 0.120396 0.2794)
			(stroke
				(width 0.1)
				(type default)
			)
			(layer "F.Fab")
		)
		(fp_line
			(start 0.67945 0.3048)
			(end 0.120396 0.3048)
			(stroke
				(width 0.1)
				(type default)
			)
			(layer "F.Fab")
		)
		(fp_line
			(start -0.12065 0.2794)
			(end -0.12065 0.3048)
			(stroke
				(width 0.1)
				(type default)
			)
			(layer "F.Fab")
		)
		(fp_line
			(start 0.120396 0.2794)
			(end -0.12065 0.2794)
			(stroke
				(width 0.1)
				(type default)
			)
			(layer "F.Fab")
		)
		(fp_line
			(start -0.12065 -0.2794)
			(end 0.12065 -0.2794)
			(stroke
				(width 0.1)
				(type default)
			)
			(layer "F.Fab")
		)
		(fp_line
			(start 0.12065 -0.2794)
			(end 0.12065 -0.3048)
			(stroke
				(width 0.1)
				(type default)
			)
			(layer "F.Fab")
		)
		(fp_line
			(start 0.12065 -0.3048)
			(end 0.67945 -0.3048)
			(stroke
				(width 0.1)
				(type default)
			)
			(layer "F.Fab")
		)
		(fp_line
			(start 0.67945 -0.3048)
			(end 0.67945 0.3048)
			(stroke
				(width 0.1)
				(type default)
			)
			(layer "F.Fab")
		)
		(fp_line
			(start -0.67945 -0.305054)
			(end -0.12065 -0.305054)
			(stroke
				(width 0.1)
				(type default)
			)
			(layer "F.Fab")
		)
		(fp_line
			(start -0.12065 -0.305054)
			(end -0.12065 -0.2794)
			(stroke
				(width 0.1)
				(type default)
			)
			(layer "F.Fab")
		)
		(pad "1" smd circle
			(at -0.40005 0 270)
			(size 0 0)
			(layers "F.Cu" "F.Mask" "F.Paste")
			(net "SMB_S3M_CPU0_PIROM_3V3AUX_SDA")
		)
		(pad "2" smd circle
			(at 0.40005 0 270)
			(size 0 0)
			(layers "F.Cu" "F.Mask" "F.Paste")
			(net "P3V3_AUX")
		)
	)
	(footprint ""
		(layer "F.Cu")
		(at 96.039686 -423.820336 -90)
		(property "Reference" "Q108"
			(at 6.415278 4.683506 0)
			(unlocked yes)
			(layer "F.SilkS")
			(effects
				(font
					(size 0.7874 0.5842)
					(thickness 0.1524)
				)
				(justify left)
			)
		)
		(property "Value" ""
			(at 0 0 270)
			(layer "F.Fab")
			(effects
				(font
					(size 1.27 1.27)
				)
			)
		)
		(duplicate_pad_numbers_are_jumpers no)
		(fp_line
			(start -1.332738 1.100074)
			(end -1.332738 -1.100074)
			(stroke
				(width 0.1524)
				(type default)
			)
			(layer "F.SilkS")
		)
		(fp_line
			(start 1.332738 1.100074)
			(end -1.332738 1.100074)
			(stroke
				(width 0.1524)
				(type default)
			)
			(layer "F.SilkS")
		)
		(fp_line
			(start 0 -0.541274)
			(end 0.4826 -1.100074)
			(stroke
				(width 0.1524)
				(type default)
			)
			(layer "F.SilkS")
		)
		(fp_line
			(start -1.332738 -1.100074)
			(end -0.4826 -1.100074)
			(stroke
				(width 0.1524)
				(type default)
			)
			(layer "F.SilkS")
		)
		(fp_line
			(start -0.4826 -1.100074)
			(end 0 -0.541274)
			(stroke
				(width 0.1524)
				(type default)
			)
			(layer "F.SilkS")
		)
		(fp_line
			(start 0.4826 -1.100074)
			(end 1.332738 -1.100074)
			(stroke
				(width 0.1524)
				(type default)
			)
			(layer "F.SilkS")
		)
		(fp_line
			(start 1.332738 -1.100074)
			(end 1.332738 1.100074)
			(stroke
				(width 0.1524)
				(type default)
			)
			(layer "F.SilkS")
		)
		(fp_poly
			(pts
				(xy -2.44856 -1.462532) (xy -1.746504 -1.111504) (xy -2.44856 -0.760476)
			)
			(stroke
				(width 0)
				(type default)
			)
			(fill yes)
			(layer "F.SilkS")
		)
		(fp_line
			(start -0.674878 1.100074)
			(end -0.674878 -1.100074)
			(stroke
				(width 0.1)
				(type default)
			)
			(layer "F.Fab")
		)
		(fp_line
			(start 0.674878 1.100074)
			(end -0.674878 1.100074)
			(stroke
				(width 0.1)
				(type default)
			)
			(layer "F.Fab")
		)
		(fp_line
			(start -0.674878 -1.100074)
			(end 0.674878 -1.100074)
			(stroke
				(width 0.1)
				(type default)
			)
			(layer "F.Fab")
		)
		(fp_line
			(start 0.674878 -1.100074)
			(end 0.674878 1.100074)
			(stroke
				(width 0.1)
				(type default)
			)
			(layer "F.Fab")
		)
		(fp_poly
			(pts
				(xy -2.2352 -0.298958) (xy -2.2352 -1.001014) (xy -1.533144 -0.649986)
			)
			(stroke
				(width 0)
				(type default)
			)
			(fill yes)
			(layer "F.Fab")
		)
		(pad "1" smd rect
			(at -0.94996 -0.649986)
			(size 0.4318 0.508)
			(layers "F.Cu" "F.Mask" "F.Paste")
			(net "GND")
		)
		(pad "2" smd rect
			(at -0.94996 0)
			(size 0.4318 0.508)
			(layers "F.Cu" "F.Mask" "F.Paste")
			(net "GPU_FPGA_EROT_FATALERR_N")
		)
		(pad "3" smd rect
			(at -0.94996 0.649986)
			(size 0.4318 0.508)
			(layers "F.Cu" "F.Mask" "F.Paste")
			(net "GPU_FPGA_EROT_FATALERR_ISO_N")
		)
		(pad "4" smd rect
			(at 0.94996 0.649986)
			(size 0.4318 0.508)
			(layers "F.Cu" "F.Mask" "F.Paste")
			(net "GND")
		)
		(pad "5" smd rect
			(at 0.94996 0)
			(size 0.4318 0.508)
			(layers "F.Cu" "F.Mask" "F.Paste")
			(net "GPU_FPGA_EROT_FATALERR")
		)
		(pad "6" smd rect
			(at 0.94996 -0.649986)
			(size 0.4318 0.508)
			(layers "F.Cu" "F.Mask" "F.Paste")
			(net "GPU_FPGA_EROT_FATALERR")
		)
	)
	(footprint ""
		(layer "F.Cu")
		(at 214.344504 -17.766792 -90)
		(property "Reference" "U90"
			(at -1.504696 -2.230882 0)
			(unlocked yes)
			(layer "F.SilkS")
			(effects
				(font
					(size 0.7874 0.5842)
					(thickness 0.1524)
				)
				(justify left)
			)
		)
		(property "Value" ""
			(at 0 0 270)
			(layer "F.Fab")
			(effects
				(font
					(size 1.27 1.27)
				)
			)
		)
		(duplicate_pad_numbers_are_jumpers no)
		(fp_line
			(start -2.25044 1.5494)
			(end -2.25044 1.3208)
			(stroke
				(width 0.1524)
				(type default)
			)
			(layer "F.SilkS")
		)
		(fp_line
			(start 2.25044 1.5494)
			(end -2.25044 1.5494)
			(stroke
				(width 0.1524)
				(type default)
			)
			(layer "F.SilkS")
		)
		(fp_line
			(start 2.25044 1.3208)
			(end 2.25044 1.5494)
			(stroke
				(width 0.1524)
				(type default)
			)
			(layer "F.SilkS")
		)
		(fp_line
			(start 0 -0.9652)
			(end -0.5842 -1.5494)
			(stroke
				(width 0.1524)
				(type default)
			)
			(layer "F.SilkS")
		)
		(fp_line
			(start 2.25044 -1.3208)
			(end 2.25044 -1.5494)
			(stroke
				(width 0.1524)
				(type default)
			)
			(layer "F.SilkS")
		)
		(fp_line
			(start -2.25044 -1.5494)
			(end -2.25044 -1.3208)
			(stroke
				(width 0.1524)
				(type default)
			)
			(layer "F.SilkS")
		)
		(fp_line
			(start -0.5842 -1.5494)
			(end -2.25044 -1.5494)
			(stroke
				(width 0.1524)
				(type default)
			)
			(layer "F.SilkS")
		)
		(fp_line
			(start 0.5842 -1.5494)
			(end 0 -0.9652)
			(stroke
				(width 0.1524)
				(type default)
			)
			(layer "F.SilkS")
		)
		(fp_line
			(start 2.0066 -1.5494)
			(end 0.5842 -1.5494)
			(stroke
				(width 0.1524)
				(type default)
			)
			(layer "F.SilkS")
		)
		(fp_line
			(start 2.25044 -1.5494)
			(end 0.5842 -1.5494)
			(stroke
				(width 0.1524)
				(type default)
			)
			(layer "F.SilkS")
		)
		(fp_poly
			(pts
				(xy -4.36372 -1.344168) (xy -3.81 -1.016) (xy -4.36372 -0.719328)
			)
			(stroke
				(width 0)
				(type default)
			)
			(fill yes)
			(layer "F.SilkS")
		)
		(fp_line
			(start -2.25044 1.5494)
			(end 2.25044 1.5494)
			(stroke
				(width 0.1)
				(type default)
			)
			(layer "F.Fab")
		)
		(fp_line
			(start -2.25044 1.5494)
			(end -2.25044 1.12522)
			(stroke
				(width 0.1)
				(type default)
			)
			(layer "F.Fab")
		)
		(fp_line
			(start 2.25044 1.5494)
			(end 2.25044 1.12522)
			(stroke
				(width 0.1)
				(type default)
			)
			(layer "F.Fab")
		)
		(fp_line
			(start 2.25044 1.5494)
			(end 2.25044 -1.5494)
			(stroke
				(width 0.1)
				(type default)
			)
			(layer "F.Fab")
		)
		(fp_line
			(start 2.25044 1.143)
			(end 2.25044 1.0922)
			(stroke
				(width 0.1)
				(type default)
			)
			(layer "F.Fab")
		)
		(fp_line
			(start -3.302 1.12522)
			(end -3.302 -1.12522)
			(stroke
				(width 0.1)
				(type default)
			)
			(layer "F.Fab")
		)
		(fp_line
			(start -2.25044 1.12522)
			(end -3.302 1.12522)
			(stroke
				(width 0.1)
				(type default)
			)
			(layer "F.Fab")
		)
		(fp_line
			(start 2.25044 1.12522)
			(end 3.302 1.12522)
			(stroke
				(width 0.1)
				(type default)
			)
			(layer "F.Fab")
		)
		(fp_line
			(start 3.302 1.12522)
			(end 3.302 -1.12522)
			(stroke
				(width 0.1)
				(type default)
			)
			(layer "F.Fab")
		)
		(fp_line
			(start -3.302 -1.12522)
			(end -2.25044 -1.12522)
			(stroke
				(width 0.1)
				(type default)
			)
			(layer "F.Fab")
		)
		(fp_line
			(start -2.25044 -1.12522)
			(end -2.25044 -1.5494)
			(stroke
				(width 0.1)
				(type default)
			)
			(layer "F.Fab")
		)
		(fp_line
			(start 2.25044 -1.12522)
			(end 2.25044 -1.4986)
			(stroke
				(width 0.1)
				(type default)
			)
			(layer "F.Fab")
		)
		(fp_line
			(start 3.302 -1.12522)
			(end 2.25044 -1.12522)
			(stroke
				(width 0.1)
				(type default)
			)
			(layer "F.Fab")
		)
		(fp_line
			(start -2.25044 -1.5494)
			(end -2.25044 1.5494)
			(stroke
				(width 0.1)
				(type default)
			)
			(layer "F.Fab")
		)
		(fp_line
			(start 2.25044 -1.5494)
			(end -2.25044 -1.5494)
			(stroke
				(width 0.1)
				(type default)
			)
			(layer "F.Fab")
		)
		(fp_poly
			(pts
				(xy -4.36372 -0.719328) (xy -4.36372 -1.344168) (xy -3.81 -1.016)
			)
			(stroke
				(width 0)
				(type default)
			)
			(fill yes)
			(layer "F.Fab")
		)
		(pad "1" smd rect
			(at -2.921 -0.975106 180)
			(size 0.3556 1.4986)
			(layers "F.Cu" "F.Mask" "F.Paste")
			(net "CLK_50M_RMII_R")
		)
		(pad "2" smd rect
			(at -2.921 -0.32512 180)
			(size 0.3556 1.4986)
			(layers "F.Cu" "F.Mask" "F.Paste")
			(net "CLK_50M_EN")
		)
		(pad "3" smd rect
			(at -2.921 0.32512 180)
			(size 0.3556 1.4986)
			(layers "F.Cu" "F.Mask" "F.Paste")
			(net "CLK_50M_BMC_MAC_R")
		)
		(pad "4" smd rect
			(at -2.921 0.975106 180)
			(size 0.3556 1.4986)
			(layers "F.Cu" "F.Mask" "F.Paste")
			(net "GND")
		)
		(pad "5" smd rect
			(at 2.921 0.975106 180)
			(size 0.3556 1.4986)
			(layers "F.Cu" "F.Mask" "F.Paste")
			(net "CLK_50M_NCSI_OCP_1")
		)
		(pad "6" smd rect
			(at 2.921 0.32512 180)
			(size 0.3556 1.4986)
			(layers "F.Cu" "F.Mask" "F.Paste")
			(net "P3V3_AUX")
		)
		(pad "7" smd rect
			(at 2.921 -0.32512 180)
			(size 0.3556 1.4986)
			(layers "F.Cu" "F.Mask" "F.Paste")
			(net "CLK_50M_NCSI_OCP_2")
		)
		(pad "8" smd rect
			(at 2.921 -0.975106 180)
			(size 0.3556 1.4986)
			(layers "F.Cu" "F.Mask" "F.Paste")
			(net "TP_CLK_50M_PCH_LOM")
		)
	)
)
